(kicad_pcb
	(version 20260206)
	(generator "pcbnew")
	(generator_version "10.0")
	(general
		(thickness 1.6)
		(legacy_teardrops no)
	)
	(paper "A4")
	(title_block
		(title "Bryce Canyon_F.DPB_16315-1-OCP.brd")
		(comment 1 "Bryce Canyon / footprints 2109-2115 of 2223")
	)
	(layers
		(0 "F.Cu" signal "TOP")
		(4 "In1.Cu" signal "L2GND")
		(6 "In2.Cu" signal "L3")
		(8 "In3.Cu" signal "L4GND")
		(10 "In4.Cu" signal "L5")
		(12 "In5.Cu" signal "L6VCC")
		(14 "In6.Cu" signal "L7VCC")
		(16 "In7.Cu" signal "L8")
		(18 "In8.Cu" signal "L9GND")
		(20 "In9.Cu" signal "L10")
		(22 "In10.Cu" signal "L11GND")
		(2 "B.Cu" signal "BOTTOM")
		(9 "F.Adhes" user "F.Adhesive")
		(11 "B.Adhes" user "B.Adhesive")
		(13 "F.Paste" user "Package Geometry/Pastemask Top")
		(15 "B.Paste" user "Package Geometry/Pastemask Bottom")
		(5 "F.SilkS" user "Ref Des/Silkscreen Top")
		(7 "B.SilkS" user "Ref Des/Silkscreen Bottom")
		(1 "F.Mask" user "Board Geometry/Soldermask Top")
		(3 "B.Mask" user "Board Geometry/Soldermask Bottom")
		(17 "Dwgs.User" user "User.Drawings")
		(19 "Cmts.User" user "User.Comments")
		(21 "Eco1.User" user "User.Eco1")
		(23 "Eco2.User" user "User.Eco2")
		(25 "Edge.Cuts" user "Board Geometry/Outline")
		(27 "Margin" user)
		(31 "F.CrtYd" user "Package Geometry/Place Bound Top")
		(29 "B.CrtYd" user "Package Geometry/Place Bound Bottom")
		(35 "F.Fab" user "Ref Des/Assembly Top")
		(33 "B.Fab" user "Ref Des/Assembly Bottom")
	)
	(footprint ""
		(layer "B.Cu")
		(at 185.212228 -219.507308)
		(property "Reference" "R1288"
			(at 0 0 0)
			(layer "B.SilkS")
			(hide yes)
			(effects
				(font
					(size 1.27 1.27)
				)
				(justify mirror)
			)
		)
		(property "Value" "10KR2F-2-GP"
			(at -0.064008 -3.993896 0)
			(unlocked yes)
			(layer "B.Fab")
			(hide yes)
			(effects
				(font
					(size 1.016 1.016)
					(thickness 0.1524)
				)
				(justify mirror)
			)
		)
		(property "Device Type" "R402H16"
			(at -0.064008 -5.517896 0)
			(unlocked yes)
			(layer "B.Fab")
			(hide yes)
			(effects
				(font
					(size 1.016 1.016)
					(thickness 0.1524)
				)
				(justify mirror)
			)
		)
		(duplicate_pad_numbers_are_jumpers no)
		(fp_line
			(start -0.508 -0.9398)
			(end 0.508 -0.9398)
			(stroke
				(width 0.1524)
				(type default)
			)
			(layer "B.SilkS")
		)
		(fp_line
			(start 0.508 -0.9398)
			(end 0.508 0.9398)
			(stroke
				(width 0.1524)
				(type default)
			)
			(layer "B.SilkS")
		)
		(fp_rect
			(start 0.508 0.9398)
			(end -0.508 -0.9398)
			(stroke
				(width 0)
				(type default)
			)
			(fill no)
			(layer "B.CrtYd")
		)
		(fp_rect
			(start 0.508 0.9398)
			(end -0.508 -0.9398)
			(stroke
				(width 0)
				(type default)
			)
			(fill no)
			(layer "B.Fab")
		)
		(pad "1" smd custom
			(at 0 -0.4445 180)
			(size 0.1397 0.1397)
			(layers "B.Cu" "B.Mask" "B.Paste")
			(net "P3V3_STBY_VRG5")
			(options
				(clearance outline)
				(anchor circle)
			)
			(primitives
				(gr_poly
					(pts
						(arc
							(start -0.1778 0.2794)
							(mid -0.249642 0.249642)
							(end -0.2794 0.1778)
						)
						(arc
							(start -0.2794 -0.1778)
							(mid -0.249642 -0.249642)
							(end -0.1778 -0.2794)
						)
						(arc
							(start 0.1778 -0.2794)
							(mid 0.249642 -0.249642)
							(end 0.2794 -0.1778)
						)
						(arc
							(start 0.2794 0.1778)
							(mid 0.249642 0.249642)
							(end 0.1778 0.2794)
						)
					)
					(width 0)
					(fill yes)
				)
			)
		)
		(pad "2" smd custom
			(at 0 0.4445 180)
			(size 0.1397 0.1397)
			(layers "B.Cu" "B.Mask" "B.Paste")
			(net "PWRGD_P3V3_STBY")
			(options
				(clearance outline)
				(anchor circle)
			)
			(primitives
				(gr_poly
					(pts
						(arc
							(start -0.1778 0.2794)
							(mid -0.249642 0.249642)
							(end -0.2794 0.1778)
						)
						(arc
							(start -0.2794 -0.1778)
							(mid -0.249642 -0.249642)
							(end -0.1778 -0.2794)
						)
						(arc
							(start 0.1778 -0.2794)
							(mid 0.249642 -0.249642)
							(end 0.2794 -0.1778)
						)
						(arc
							(start 0.2794 0.1778)
							(mid 0.249642 0.249642)
							(end 0.1778 0.2794)
						)
					)
					(width 0)
					(fill yes)
				)
			)
		)
	)
	(footprint ""
		(layer "B.Cu")
		(at 456.880214 -255.941576 180)
		(property "Reference" "C642"
			(at 0 0 0)
			(layer "B.SilkS")
			(hide yes)
			(effects
				(font
					(size 1.27 1.27)
				)
				(justify mirror)
			)
		)
		(property "Value" "SCD1U50V3KX-GP"
			(at 0 -2.8194 180)
			(unlocked yes)
			(layer "B.Fab")
			(hide yes)
			(effects
				(font
					(size 1.016 1.016)
					(thickness 0.1524)
				)
				(justify mirror)
			)
		)
		(property "Device Type" "C603H36"
			(at 0 -4.3434 180)
			(unlocked yes)
			(layer "B.Fab")
			(hide yes)
			(effects
				(font
					(size 1.016 1.016)
					(thickness 0.1524)
				)
				(justify mirror)
			)
		)
		(duplicate_pad_numbers_are_jumpers no)
		(fp_line
			(start -0.508 0)
			(end 0.508 0)
			(stroke
				(width 0.2032)
				(type default)
			)
			(layer "B.SilkS")
		)
		(fp_rect
			(start 0.5842 1.3335)
			(end -0.5842 -1.3335)
			(stroke
				(width 0)
				(type default)
			)
			(fill no)
			(layer "B.CrtYd")
		)
		(fp_rect
			(start 0.5842 1.3335)
			(end -0.5842 -1.3335)
			(stroke
				(width 0)
				(type default)
			)
			(fill no)
			(layer "B.Fab")
		)
		(pad "1" smd custom
			(at 0 -0.762)
			(size 0.2159 0.2159)
			(layers "B.Cu" "B.Mask" "B.Paste")
			(net "P5V_A_3")
			(options
				(clearance outline)
				(anchor circle)
			)
			(primitives
				(gr_poly
					(pts
						(arc
							(start -0.3302 0.4318)
							(mid -0.402042 0.402042)
							(end -0.4318 0.3302)
						)
						(arc
							(start -0.4318 -0.3302)
							(mid -0.402042 -0.402042)
							(end -0.3302 -0.4318)
						)
						(arc
							(start 0.3302 -0.4318)
							(mid 0.402042 -0.402042)
							(end 0.4318 -0.3302)
						)
						(arc
							(start 0.4318 0.3302)
							(mid 0.402042 0.402042)
							(end 0.3302 0.4318)
						)
					)
					(width 0)
					(fill yes)
				)
			)
		)
		(pad "2" smd custom
			(at 0 0.762)
			(size 0.2159 0.2159)
			(layers "B.Cu" "B.Mask" "B.Paste")
			(net "P5V_C_LL_R")
			(options
				(clearance outline)
				(anchor circle)
			)
			(primitives
				(gr_poly
					(pts
						(arc
							(start -0.3302 0.4318)
							(mid -0.402042 0.402042)
							(end -0.4318 0.3302)
						)
						(arc
							(start -0.4318 -0.3302)
							(mid -0.402042 -0.402042)
							(end -0.3302 -0.4318)
						)
						(arc
							(start 0.3302 -0.4318)
							(mid 0.402042 -0.402042)
							(end 0.4318 -0.3302)
						)
						(arc
							(start 0.4318 0.3302)
							(mid 0.402042 0.402042)
							(end 0.3302 0.4318)
						)
					)
					(width 0)
					(fill yes)
				)
			)
		)
	)
	(footprint ""
		(layer "B.Cu")
		(at 221.488 -123.444)
		(property "Reference" "R369"
			(at 0 0 0)
			(layer "B.SilkS")
			(hide yes)
			(effects
				(font
					(size 1.27 1.27)
				)
				(justify mirror)
			)
		)
		(property "Value" "0R2J-2-GP"
			(at -0.064008 -3.993896 0)
			(unlocked yes)
			(layer "B.Fab")
			(hide yes)
			(effects
				(font
					(size 1.016 1.016)
					(thickness 0.1524)
				)
				(justify mirror)
			)
		)
		(property "Device Type" "R402H16"
			(at -0.064008 -5.517896 0)
			(unlocked yes)
			(layer "B.Fab")
			(hide yes)
			(effects
				(font
					(size 1.016 1.016)
					(thickness 0.1524)
				)
				(justify mirror)
			)
		)
		(duplicate_pad_numbers_are_jumpers no)
		(fp_line
			(start -0.508 -0.9398)
			(end 0.508 -0.9398)
			(stroke
				(width 0.1524)
				(type default)
			)
			(layer "B.SilkS")
		)
		(fp_line
			(start 0.508 -0.9398)
			(end 0.508 0.9398)
			(stroke
				(width 0.1524)
				(type default)
			)
			(layer "B.SilkS")
		)
		(fp_rect
			(start 0.508 0.9398)
			(end -0.508 -0.9398)
			(stroke
				(width 0)
				(type default)
			)
			(fill no)
			(layer "B.CrtYd")
		)
		(fp_rect
			(start 0.508 0.9398)
			(end -0.508 -0.9398)
			(stroke
				(width 0)
				(type default)
			)
			(fill no)
			(layer "B.Fab")
		)
		(pad "1" smd custom
			(at 0 -0.4445 180)
			(size 0.1397 0.1397)
			(layers "B.Cu" "B.Mask" "B.Paste")
			(net "COMP_A_PGOOD")
			(options
				(clearance outline)
				(anchor circle)
			)
			(primitives
				(gr_poly
					(pts
						(arc
							(start -0.1778 0.2794)
							(mid -0.249642 0.249642)
							(end -0.2794 0.1778)
						)
						(arc
							(start -0.2794 -0.1778)
							(mid -0.249642 -0.249642)
							(end -0.1778 -0.2794)
						)
						(arc
							(start 0.1778 -0.2794)
							(mid 0.249642 -0.249642)
							(end 0.2794 -0.1778)
						)
						(arc
							(start 0.2794 0.1778)
							(mid 0.249642 0.249642)
							(end 0.1778 0.2794)
						)
					)
					(width 0)
					(fill yes)
				)
			)
		)
		(pad "2" smd custom
			(at 0 0.4445 180)
			(size 0.1397 0.1397)
			(layers "B.Cu" "B.Mask" "B.Paste")
			(net "TXS0102_A_OE")
			(options
				(clearance outline)
				(anchor circle)
			)
			(primitives
				(gr_poly
					(pts
						(arc
							(start -0.1778 0.2794)
							(mid -0.249642 0.249642)
							(end -0.2794 0.1778)
						)
						(arc
							(start -0.2794 -0.1778)
							(mid -0.249642 -0.249642)
							(end -0.1778 -0.2794)
						)
						(arc
							(start 0.1778 -0.2794)
							(mid 0.249642 -0.249642)
							(end 0.2794 -0.1778)
						)
						(arc
							(start 0.2794 0.1778)
							(mid 0.249642 0.249642)
							(end 0.1778 0.2794)
						)
					)
					(width 0)
					(fill yes)
				)
			)
		)
	)
	(footprint ""
		(layer "B.Cu")
		(at 432.608482 -252.098302)
		(property "Reference" "L5"
			(at 0 0 0)
			(layer "B.SilkS")
			(hide yes)
			(effects
				(font
					(size 1.27 1.27)
				)
				(justify mirror)
			)
		)
		(property "Value" "BLM21PG220SN1DGP"
			(at -0.0254 -5.6896 0)
			(unlocked yes)
			(layer "B.Fab")
			(hide yes)
			(effects
				(font
					(size 1.016 1.016)
					(thickness 0.1524)
				)
				(justify mirror)
			)
		)
		(property "Device Type" "L20125H42"
			(at -0.0254 -7.5946 0)
			(unlocked yes)
			(layer "B.Fab")
			(hide yes)
			(effects
				(font
					(size 1.016 1.016)
					(thickness 0.1524)
				)
				(justify mirror)
			)
		)
		(duplicate_pad_numbers_are_jumpers no)
		(fp_line
			(start -0.9144 -1.7018)
			(end 0.9144 -1.7018)
			(stroke
				(width 0.1524)
				(type default)
			)
			(layer "B.SilkS")
		)
		(fp_line
			(start -0.9144 1.7018)
			(end -0.9144 -1.7018)
			(stroke
				(width 0.1524)
				(type default)
			)
			(layer "B.SilkS")
		)
		(fp_line
			(start 0.9144 -1.7018)
			(end 0.9144 1.7018)
			(stroke
				(width 0.1524)
				(type default)
			)
			(layer "B.SilkS")
		)
		(fp_line
			(start 0.9144 1.7018)
			(end -0.9144 1.7018)
			(stroke
				(width 0.1524)
				(type default)
			)
			(layer "B.SilkS")
		)
		(fp_rect
			(start 1.0033 1.778)
			(end -1.0033 -1.778)
			(stroke
				(width 0)
				(type default)
			)
			(fill no)
			(layer "B.CrtYd")
		)
		(fp_poly
			(pts
				(xy 1.0033 -1.778) (xy -1.0033 -1.778) (xy -1.0033 1.778) (xy 1.0033 1.778)
			)
			(stroke
				(width 0)
				(type default)
			)
			(fill no)
			(layer "B.Fab")
		)
		(pad "1" smd rect
			(at 0 -0.9652 180)
			(size 1.397 1.143)
			(layers "B.Cu" "B.Mask" "B.Paste")
			(net "P12V_A")
		)
		(pad "2" smd rect
			(at 0 0.9652 180)
			(size 1.397 1.143)
			(layers "B.Cu" "B.Mask" "B.Paste")
			(net "P12V_A_VIN_U22")
		)
	)
	(footprint ""
		(layer "B.Cu")
		(at 478.71888 -222.229172 90)
		(property "Reference" "C658"
			(at 0 0 90)
			(layer "B.SilkS")
			(hide yes)
			(effects
				(font
					(size 1.27 1.27)
				)
				(justify mirror)
			)
		)
		(property "Value" "SCD1U50V3KX-GP"
			(at 0 -2.8194 90)
			(unlocked yes)
			(layer "B.Fab")
			(hide yes)
			(effects
				(font
					(size 1.016 1.016)
					(thickness 0.1524)
				)
				(justify mirror)
			)
		)
		(property "Device Type" "C603H36"
			(at 0 -4.3434 90)
			(unlocked yes)
			(layer "B.Fab")
			(hide yes)
			(effects
				(font
					(size 1.016 1.016)
					(thickness 0.1524)
				)
				(justify mirror)
			)
		)
		(duplicate_pad_numbers_are_jumpers no)
		(fp_line
			(start -0.508 0)
			(end 0.508 0)
			(stroke
				(width 0.2032)
				(type default)
			)
			(layer "B.SilkS")
		)
		(fp_rect
			(start 0.5842 1.3335)
			(end -0.5842 -1.3335)
			(stroke
				(width 0)
				(type default)
			)
			(fill no)
			(layer "B.CrtYd")
		)
		(fp_rect
			(start 0.5842 1.3335)
			(end -0.5842 -1.3335)
			(stroke
				(width 0)
				(type default)
			)
			(fill no)
			(layer "B.Fab")
		)
		(pad "1" smd custom
			(at 0 -0.762 270)
			(size 0.2159 0.2159)
			(layers "B.Cu" "B.Mask" "B.Paste")
			(net "P5V_A_4")
			(options
				(clearance outline)
				(anchor circle)
			)
			(primitives
				(gr_poly
					(pts
						(arc
							(start -0.3302 0.4318)
							(mid -0.402042 0.402042)
							(end -0.4318 0.3302)
						)
						(arc
							(start -0.4318 -0.3302)
							(mid -0.402042 -0.402042)
							(end -0.3302 -0.4318)
						)
						(arc
							(start 0.3302 -0.4318)
							(mid 0.402042 -0.402042)
							(end 0.4318 -0.3302)
						)
						(arc
							(start 0.4318 0.3302)
							(mid 0.402042 0.402042)
							(end 0.3302 0.4318)
						)
					)
					(width 0)
					(fill yes)
				)
			)
		)
		(pad "2" smd custom
			(at 0 0.762 270)
			(size 0.2159 0.2159)
			(layers "B.Cu" "B.Mask" "B.Paste")
			(net "P5V_D_LL_R")
			(options
				(clearance outline)
				(anchor circle)
			)
			(primitives
				(gr_poly
					(pts
						(arc
							(start -0.3302 0.4318)
							(mid -0.402042 0.402042)
							(end -0.4318 0.3302)
						)
						(arc
							(start -0.4318 -0.3302)
							(mid -0.402042 -0.402042)
							(end -0.3302 -0.4318)
						)
						(arc
							(start 0.3302 -0.4318)
							(mid 0.402042 -0.402042)
							(end 0.4318 -0.3302)
						)
						(arc
							(start 0.4318 0.3302)
							(mid 0.402042 0.402042)
							(end 0.3302 0.4318)
						)
					)
					(width 0)
					(fill yes)
				)
			)
		)
	)
	(footprint ""
		(layer "B.Cu")
		(at 35.007804 -253.426214 -90)
		(property "Reference" "R1216"
			(at 0 0 90)
			(layer "B.SilkS")
			(hide yes)
			(effects
				(font
					(size 1.27 1.27)
				)
				(justify mirror)
			)
		)
		(property "Value" "10R3F-GP"
			(at 0.0254 -2.5146 270)
			(unlocked yes)
			(layer "B.Fab")
			(hide yes)
			(effects
				(font
					(size 1.016 1.016)
					(thickness 0.1524)
				)
				(justify mirror)
			)
		)
		(property "Device Type" "R603H22"
			(at 0.0254 -4.0386 270)
			(unlocked yes)
			(layer "B.Fab")
			(hide yes)
			(effects
				(font
					(size 1.016 1.016)
					(thickness 0.1524)
				)
				(justify mirror)
			)
		)
		(duplicate_pad_numbers_are_jumpers no)
		(fp_line
			(start -0.2032 0)
			(end -0.4826 0)
			(stroke
				(width 0.2032)
				(type default)
			)
			(layer "B.SilkS")
		)
		(fp_line
			(start 0.4826 0)
			(end 0.2032 0)
			(stroke
				(width 0.2032)
				(type default)
			)
			(layer "B.SilkS")
		)
		(fp_rect
			(start 0.5842 1.3335)
			(end -0.5842 -1.3335)
			(stroke
				(width 0)
				(type default)
			)
			(fill no)
			(layer "B.CrtYd")
		)
		(fp_rect
			(start 0.5842 1.3335)
			(end -0.5842 -1.3335)
			(stroke
				(width 0)
				(type default)
			)
			(fill no)
			(layer "B.Fab")
		)
		(pad "1" smd custom
			(at 0 -0.762 90)
			(size 0.2159 0.2159)
			(layers "B.Cu" "B.Mask" "B.Paste")
			(net "P5V_A_CC")
			(options
				(clearance outline)
				(anchor circle)
			)
			(primitives
				(gr_poly
					(pts
						(arc
							(start -0.3302 0.4318)
							(mid -0.402042 0.402042)
							(end -0.4318 0.3302)
						)
						(arc
							(start -0.4318 -0.3302)
							(mid -0.402042 -0.402042)
							(end -0.3302 -0.4318)
						)
						(arc
							(start 0.3302 -0.4318)
							(mid 0.402042 -0.402042)
							(end 0.4318 -0.3302)
						)
						(arc
							(start 0.4318 0.3302)
							(mid 0.402042 0.402042)
							(end 0.3302 0.4318)
						)
					)
					(width 0)
					(fill yes)
				)
			)
		)
		(pad "2" smd custom
			(at 0 0.762 90)
			(size 0.2159 0.2159)
			(layers "B.Cu" "B.Mask" "B.Paste")
			(net "P5V_A_VFB_R")
			(options
				(clearance outline)
				(anchor circle)
			)
			(primitives
				(gr_poly
					(pts
						(arc
							(start -0.3302 0.4318)
							(mid -0.402042 0.402042)
							(end -0.4318 0.3302)
						)
						(arc
							(start -0.4318 -0.3302)
							(mid -0.402042 -0.402042)
							(end -0.3302 -0.4318)
						)
						(arc
							(start 0.3302 -0.4318)
							(mid 0.402042 -0.402042)
							(end 0.4318 -0.3302)
						)
						(arc
							(start 0.4318 0.3302)
							(mid 0.402042 0.402042)
							(end 0.3302 0.4318)
						)
					)
					(width 0)
					(fill yes)
				)
			)
		)
	)
	(footprint ""
		(layer "B.Cu")
		(at 465.6328 -244.094)
		(property "Reference" "TC11"
			(at 0 0 0)
			(layer "B.SilkS")
			(hide yes)
			(effects
				(font
					(size 1.27 1.27)
				)
				(justify mirror)
			)
		)
		(property "Value" "ST220U10VDM-LGP"
			(at 0 -9.6012 0)
			(unlocked yes)
			(layer "B.Fab")
			(hide yes)
			(effects
				(font
					(size 1.016 1.016)
					(thickness 0.1524)
				)
				(justify mirror)
			)
		)
		(property "Device Type" "CT7343H119"
			(at 0 -11.1252 0)
			(unlocked yes)
			(layer "B.Fab")
			(hide yes)
			(effects
				(font
					(size 1.016 1.016)
					(thickness 0.1524)
				)
				(justify mirror)
			)
		)
		(duplicate_pad_numbers_are_jumpers no)
		(fp_line
			(start -2.286 -4.8768)
			(end 2.286 -4.8768)
			(stroke
				(width 0.1524)
				(type default)
			)
			(layer "B.SilkS")
		)
		(fp_line
			(start -2.286 -2.032)
			(end -2.286 -4.8768)
			(stroke
				(width 0.1524)
				(type default)
			)
			(layer "B.SilkS")
		)
		(fp_line
			(start -2.286 2.032)
			(end -2.286 4.8768)
			(stroke
				(width 0.1524)
				(type default)
			)
			(layer "B.SilkS")
		)
		(fp_line
			(start -2.286 4.8768)
			(end 2.286 4.8768)
			(stroke
				(width 0.1524)
				(type default)
			)
			(layer "B.SilkS")
		)
		(fp_line
			(start -2.1082 -4.699)
			(end 2.1082 -4.699)
			(stroke
				(width 0.508)
				(type default)
			)
			(layer "B.SilkS")
		)
		(fp_line
			(start 2.286 -4.8768)
			(end 2.286 -2.032)
			(stroke
				(width 0.1524)
				(type default)
			)
			(layer "B.SilkS")
		)
		(fp_line
			(start 2.286 4.8768)
			(end 2.286 2.032)
			(stroke
				(width 0.1524)
				(type default)
			)
			(layer "B.SilkS")
		)
		(fp_rect
			(start 2.1463 3.6449)
			(end -2.1463 -3.6449)
			(stroke
				(width 0)
				(type default)
			)
			(fill no)
			(layer "B.CrtYd")
		)
		(fp_poly
			(pts
				(xy 2.54 4.953) (xy 2.54 4.2926) (xy 3.81 4.2926) (xy 3.81 -4.2926) (xy 2.54 -4.2926) (xy 2.54 -4.953)
				(xy -2.54 -4.953) (xy -2.54 -4.2926) (xy -3.81 -4.2926) (xy -3.81 -1.6256) (xy -2.1463 -1.6256)
				(xy -2.1463 -3.6449) (xy 2.1463 -3.6449) (xy 2.1463 3.6449) (xy -2.1463 3.6449) (xy -2.1463 -1.6129)
				(xy -3.81 -1.6129) (xy -3.81 4.2926) (xy -2.54 4.2926) (xy -2.54 4.953)
			)
			(stroke
				(width 0)
				(type default)
			)
			(fill no)
			(layer "B.CrtYd")
		)
		(fp_rect
			(start -2.54 4.2926)
			(end -3.81 -4.2926)
			(stroke
				(width 0)
				(type default)
			)
			(fill no)
			(layer "B.Fab")
		)
		(fp_rect
			(start 2.54 4.953)
			(end -2.54 -4.953)
			(stroke
				(width 0)
				(type default)
			)
			(fill no)
			(layer "B.Fab")
		)
		(fp_rect
			(start 3.81 4.2926)
			(end 2.54 -4.2926)
			(stroke
				(width 0)
				(type default)
			)
			(fill no)
			(layer "B.Fab")
		)
		(pad "1" smd rect
			(at 0 -3.1496 180)
			(size 2.413 2.286)
			(layers "B.Cu" "B.Mask" "B.Paste")
			(net "P5V_A_3")
		)
		(pad "2" smd rect
			(at 0 3.1496 180)
			(size 2.413 2.286)
			(layers "B.Cu" "B.Mask" "B.Paste")
			(net "GND")
		)
		(zone
			(layer "B.Cu")
			(hatch none 0.5)
			(connect_pads
				(clearance 0)
			)
			(min_thickness 0.25)
			(keepout
				(tracks allowed)
				(vias not_allowed)
				(pads allowed)
				(copperpour not_allowed)
				(footprints allowed)
			)
			(placement
				(enabled no)
				(sheetname "")
			)
			(fill
				(thermal_gap 0.5)
				(thermal_bridge_width 0.5)
				(island_removal_mode 0)
			)
			(polygon
				(pts
					(xy 464.1215 -245.7831) (xy 464.1215 -248.6914) (xy 467.1441 -248.6914) (xy 467.1441 -245.7958)
					(xy 467.1441 -245.4656) (xy 464.1215 -245.4656)
				)
			)
		)
		(zone
			(layer "B.Cu")
			(hatch none 0.5)
			(connect_pads
				(clearance 0)
			)
			(min_thickness 0.25)
			(keepout
				(tracks allowed)
				(vias not_allowed)
				(pads allowed)
				(copperpour not_allowed)
				(footprints allowed)
			)
			(placement
				(enabled no)
				(sheetname "")
			)
			(fill
				(thermal_gap 0.5)
				(thermal_bridge_width 0.5)
				(island_removal_mode 0)
			)
			(polygon
				(pts
					(xy 467.1441 -239.4966) (xy 464.1215 -239.4966) (xy 464.1215 -242.3922) (xy 464.1215 -242.7224)
					(xy 467.1441 -242.7224) (xy 467.1441 -242.3922)
				)
			)
		)
	)
)
